# T6G (Grand Teton) — schematic netlist excerpt (pin names and nets, part order shuffled) for the footprints in the layout excerpt that follows; sources: Cadence DE-HDL packaged netlist, KiCad conversion of 04192023_DAF0TMB3IC0_F0TG_MB_C_brd_V02_OCP.brd

J24  SCONN288_DDR506112002KQ  IO  pkg DDR288S_1-1VXC  page 98
  VIN_BULK0  = P12V_MEM_CPU1
  RFU0  = NC
  VIN_MGMT  = P3V3_AUX
  HSCL  = I3C_SPD_DDRA_CPU1_SCL
  HSDA  = I3C_SPD_DDRA_CPU1_SDA
  VSS0  = GND
  DQ0_A  = M_A_CPU1_SA_DQ<0>
  VSS1  = GND
  DQ1_A  = M_A_CPU1_SA_DQ<1>
  VSS2  = GND
  DQS0_A_T  = M_A_CPU1_SA_DQS_DP<0>
  DQS0_A_C  = M_A_CPU1_SA_DQS_DN<0>
  VSS3  = GND
  DQ4_A  = M_A_CPU1_SA_DQ<4>
  VSS4  = GND
  DQ5_A  = M_A_CPU1_SA_DQ<5>
  VSS5  = GND
  DQ8_A  = M_A_CPU1_SA_DQ<8>
  VSS6  = GND
  DQ9_A  = M_A_CPU1_SA_DQ<9>
  VSS7  = GND
  DQS1_A_T  = M_A_CPU1_SA_DQS_DP<1>
  DQS1_A_C  = M_A_CPU1_SA_DQS_DN<1>
  VSS8  = GND
  DQ12_A  = M_A_CPU1_SA_DQ<12>
  VSS9  = GND
  DQ13_A  = M_A_CPU1_SA_DQ<13>
  VSS10  = GND
  DQ16_A  = M_A_CPU1_SA_DQ<16>
  VSS11  = GND
  DQ17_A  = M_A_CPU1_SA_DQ<17>
  VSS12  = GND
  DQS2_A_T  = M_A_CPU1_SA_DQS_DP<2>
  DQS2_A_C  = M_A_CPU1_SA_DQS_DN<2>
  VSS13  = GND
  DQ20_A  = M_A_CPU1_SA_DQ<20>
  VSS14  = GND
  DQ21_A  = M_A_CPU1_SA_DQ<21>
  VSS15  = GND
  DQ24_A  = M_A_CPU1_SA_DQ<24>
  VSS16  = GND
  DQ25_A  = M_A_CPU1_SA_DQ<25>
  VSS17  = GND
  DQS3_A_T  = M_A_CPU1_SA_DQS_DP<3>
  DQS3_A_C  = M_A_CPU1_SA_DQS_DN<3>
  VSS18  = GND
  DQ28_A  = M_A_CPU1_SA_DQ<28>
  VSS19  = GND
  DQ29_A  = M_A_CPU1_SA_DQ<29>
  VSS20  = GND
  CB0_A  = M_A_CPU1_SA_CB<0>
  VSS21  = GND
  CB1_A  = M_A_CPU1_SA_CB<1>
  VSS22  = GND
  DQS4_A_T  = M_A_CPU1_SA_DQS_DP<4>
  DQS4_A_C  = M_A_CPU1_SA_DQS_DN<4>
  VSS23  = GND
  CB4_A  = M_A_CPU1_SA_CB<4>
  VSS24  = GND
  CB5_A  = M_A_CPU1_SA_CB<5>
  VSS25  = GND
  ALERT_N  = M_A_CPU1_ALERT_N
  VSS26  = GND
  CS0_A_N  = M_A_CPU1_SA_CS_N<0>
  VSS27  = GND
  CA0_A  = M_A_CPU1_SA_CA<0>
  VSS28  = GND
  CA2_A  = M_A_CPU1_SA_CA<2>
  VSS29  = GND
  CA4_A  = M_A_CPU1_SA_CA<4>
  VSS30  = GND
  CA6_A  = M_A_CPU1_SA_CA<6>
  VSS31  = GND
  PAR_A  = M_A_CPU1_SA_PAR
  VSS32  = GND
  CA0_B  = M_A_CPU1_SB_CA<0>
  VSS33  = GND
  CA2_B  = M_A_CPU1_SB_CA<2>
  VSS34  = GND
  CA4_B  = M_A_CPU1_SB_CA<4>
  VSS35  = GND
  CA6_B  = M_A_CPU1_SB_CA<6>
  VSS36  = GND
  CS0_B_N  = M_A_CPU1_SB_CS_N<0>
  VSS37  = GND
  \lbd||rsp_a_n\  = M_A_CPU1_SA_RSP<0>
  \lbs||rsp_b_n\  = M_A_CPU1_SB_RSP<0>
  VSS38  = GND
  CB4_B  = M_A_CPU1_SB_CB<4>
  VSS39  = GND
  CB5_B  = M_A_CPU1_SB_CB<5>
  VSS40  = GND
  \dqs9_b_t||tdqs9_b_t||dbi4_b_n\  = M_A_CPU1_SB_DQS_DP<9>
  \dqs9_b_c||tdqs9_b_c\  = M_A_CPU1_SB_DQS_DN<9>
  VSS41  = GND
  CB0_B  = M_A_CPU1_SB_CB<0>
  VSS42  = GND
  CB1_B  = M_A_CPU1_SB_CB<1>
  VSS43  = GND
  DQ0_B  = M_A_CPU1_SB_DQ<0>
  VSS44  = GND
  DQ1_B  = M_A_CPU1_SB_DQ<1>
  VSS45  = GND
  DQS0_B_T  = M_A_CPU1_SB_DQS_DP<0>
  DQS0_B_C  = M_A_CPU1_SB_DQS_DN<0>
  VSS46  = GND
  DQ4_B  = M_A_CPU1_SB_DQ<4>
  VSS47  = GND
  DQ5_B  = M_A_CPU1_SB_DQ<5>
  VSS48  = GND
  DQ8_B  = M_A_CPU1_SB_DQ<8>
  VSS49  = GND
  DQ9_B  = M_A_CPU1_SB_DQ<9>
  VSS50  = GND
  DQS1_B_T  = M_A_CPU1_SB_DQS_DP<1>
  DQS1_B_C  = M_A_CPU1_SB_DQS_DN<1>
  VSS51  = GND
  DQ12_B  = M_A_CPU1_SB_DQ<12>
  VSS52  = GND
  DQ13_B  = M_A_CPU1_SB_DQ<13>
  VSS53  = GND
  DQ16_B  = M_A_CPU1_SB_DQ<16>
  VSS54  = GND
  DQ17_B  = M_A_CPU1_SB_DQ<17>
  VSS55  = GND
  DQS2_B_T  = M_A_CPU1_SB_DQS_DP<2>
  DQS2_B_C  = M_A_CPU1_SB_DQS_DN<2>
  VSS56  = GND
  DQ20_B  = M_A_CPU1_SB_DQ<20>
  VSS57  = GND
  DQ21_B  = M_A_CPU1_SB_DQ<21>
  VSS58  = GND
  DQ24_B  = M_A_CPU1_SB_DQ<24>
  VSS59  = GND
  DQ25_B  = M_A_CPU1_SB_DQ<25>
  VSS60  = GND
  DQS3_B_T  = M_A_CPU1_SB_DQS_DP<3>
  DQS3_B_C  = M_A_CPU1_SB_DQS_DN<3>
  VSS61  = GND
  DQ28_B  = M_A_CPU1_SB_DQ<28>
  VSS62  = GND
  DQ29_B  = M_A_CPU1_SB_DQ<29>
  VSS63  = GND
  RFU1  = NC
  VIN_BULK1  = P12V_MEM_CPU1
  VIN_BULK2  = P12V_MEM_CPU1
  \pwr_good||fail_n\  = PWRGD_CHA_CPU1_DIMM0
  HAS  = PD_CHA_CPU1_DIMM0_SAA
  RFU2  = NC
  RFU3  = NC
  VSS64  = GND
  DQ2_A  = M_A_CPU1_SA_DQ<2>
  VSS65  = GND
  DQ3_A  = M_A_CPU1_SA_DQ<3>
  VSS66  = GND
  \dqs5_a_c||tdqs5_a_c||dqs5_a_t||tdqs5_a_t\  = M_A_CPU1_SA_DQS_DN<5>
  \dqs5_a_t||tdqs5_a_t\  = M_A_CPU1_SA_DQS_DP<5>
  VSS67  = GND
  DQ6_A  = M_A_CPU1_SA_DQ<6>
  VSS68  = GND
  DQ7_A  = M_A_CPU1_SA_DQ<7>
  VSS69  = GND
  DQ10_A  = M_A_CPU1_SA_DQ<10>
  VSS70  = GND
  DQ11_A  = M_A_CPU1_SA_DQ<11>
  VSS71  = GND
  \dqs6_a_c||tdqs6_a_c||dqs6_a_t||tdqs6_a_t\  = M_A_CPU1_SA_DQS_DN<6>
  \dqs6_a_t||tdqs6_a_t\  = M_A_CPU1_SA_DQS_DP<6>
  VSS72  = GND
  DQ14_A  = M_A_CPU1_SA_DQ<14>
  VSS73  = GND
  DQ15_A  = M_A_CPU1_SA_DQ<15>
  VSS74  = GND
  DQ18_A  = M_A_CPU1_SA_DQ<18>
  VSS75  = GND
  DQ19_A  = M_A_CPU1_SA_DQ<19>
  VSS76  = GND
  \dqs7_a_c||tdqs7_a_c\  = M_A_CPU1_SA_DQS_DN<7>
  \dqs7_a_t||tdqs7_a_t\  = M_A_CPU1_SA_DQS_DP<7>
  VSS77  = GND
  DQ22_A  = M_A_CPU1_SA_DQ<22>
  VSS78  = GND
  DQ23_A  = M_A_CPU1_SA_DQ<23>
  VSS79  = GND
  DQ26_A  = M_A_CPU1_SA_DQ<26>
  VSS80  = GND
  DQ27_A  = M_A_CPU1_SA_DQ<27>
  VSS81  = GND
  \dqs8_a_c||tdqs8_a_c\  = M_A_CPU1_SA_DQS_DN<8>
  \dqs8_a_t||tdqs8_a_t\  = M_A_CPU1_SA_DQS_DP<8>
  VSS82  = GND
  DQ30_A  = M_A_CPU1_SA_DQ<30>
  VSS83  = GND
  DQ31_A  = M_A_CPU1_SA_DQ<31>
  VSS84  = GND
  CB2_A  = M_A_CPU1_SA_CB<2>
  VSS85  = GND
  CB3_A  = M_A_CPU1_SA_CB<3>
  VSS86  = GND
  \dqs9_a_c||tdqs9_a_c\  = M_A_CPU1_SA_DQS_DN<9>
  \dqs9_a_t||tdqs9_a_t\  = M_A_CPU1_SA_DQS_DP<9>
  VSS87  = GND
  CB6_A  = M_A_CPU1_SA_CB<6>
  VSS88  = GND
  CB7_A  = M_A_CPU1_SA_CB<7>
  VSS89  = GND
  RESET_N  = M_A_CPU1_RESET_N
  VSS90  = GND
  CS1_A_N  = M_A_CPU1_SA_CS_N<1>
  VSS91  = GND
  CA1_A  = M_A_CPU1_SA_CA<1>
  VSS92  = GND
  CA3_A  = M_A_CPU1_SA_CA<3>
  VSS93  = GND
  CA5_A  = M_A_CPU1_SA_CA<5>
  VSS94  = GND
  CK_T  = M_A_CPU1_CLK_DP<0>
  CK_C  = M_A_CPU1_CLK_DN<0>
  VSS95  = GND
  RFU4  = NC
  CA1_B  = M_A_CPU1_SB_CA<1>
  VSS96  = GND
  CA3_B  = M_A_CPU1_SB_CA<3>
  VSS97  = GND
  CA5_B  = M_A_CPU1_SB_CA<5>
  VSS98  = GND
  PAR_B  = M_A_CPU1_SB_PAR
  VSS99  = GND
  CS1_B_N  = M_A_CPU1_SB_CS_N<1>
  VSS100  = GND
  RFU5  = NC
  RFU6  = NC
  VSS101  = GND
  CB6_B  = M_A_CPU1_SB_CB<6>
  VSS102  = GND
  CB7_B  = M_A_CPU1_SB_CB<7>
  VSS103  = GND
  DQS4_B_C  = M_A_CPU1_SB_DQS_DN<4>
  DQS4_B_T  = M_A_CPU1_SB_DQS_DP<4>
  VSS104  = GND
  CB2_B  = M_A_CPU1_SB_CB<2>
  VSS105  = GND
  CB3_B  = M_A_CPU1_SB_CB<3>
  VSS106  = GND
  DQ2_B  = M_A_CPU1_SB_DQ<2>
  VSS107  = GND
  DQ3_B  = M_A_CPU1_SB_DQ<3>
  VSS108  = GND
  \dqs5_b_c||tdqs5_b_c\  = M_A_CPU1_SB_DQS_DN<5>
  \dqs5_b_t||tdqs5_b_t\  = M_A_CPU1_SB_DQS_DP<5>
  VSS109  = GND
  DQ6_B  = M_A_CPU1_SB_DQ<6>
  VSS110  = GND
  DQ7_B  = M_A_CPU1_SB_DQ<7>
  VSS111  = GND
  DQ10_B  = M_A_CPU1_SB_DQ<10>
  VSS112  = GND
  DQ11_B  = M_A_CPU1_SB_DQ<11>
  VSS113  = GND
  \dqs6_b_c||tdqs6_b_c\  = M_A_CPU1_SB_DQS_DN<6>
  \dqs6_b_t||tdqs6_b_t\  = M_A_CPU1_SB_DQS_DP<6>
  VSS114  = GND
  DQ14_B  = M_A_CPU1_SB_DQ<14>
  VSS115  = GND
  DQ15_B  = M_A_CPU1_SB_DQ<15>
  VSS116  = GND
  DQ18_B  = M_A_CPU1_SB_DQ<18>
  VSS117  = GND
  DQ19_B  = M_A_CPU1_SB_DQ<19>
  VSS118  = GND
  \dqs7_b_c||tdqs7_b_c\  = M_A_CPU1_SB_DQS_DN<7>
  \dqs7_b_t||tdqs7_b_t\  = M_A_CPU1_SB_DQS_DP<7>
  VSS119  = GND
  DQ22_B  = M_A_CPU1_SB_DQ<22>
  VSS120  = GND
  DQ23_B  = M_A_CPU1_SB_DQ<23>
  VSS121  = GND
  DQ26_B  = M_A_CPU1_SB_DQ<26>
  VSS122  = GND
  DQ27_B  = M_A_CPU1_SB_DQ<27>
  VSS123  = GND
  \dqs8_b_c||tdqs8_b_c\  = M_A_CPU1_SB_DQS_DN<8>
  \dqs8_b_t||tdqs8_b_t\  = M_A_CPU1_SB_DQS_DP<8>
  VSS124  = GND
  DQ30_B  = M_A_CPU1_SB_DQ<30>
  VSS125  = GND
  DQ31_B  = M_A_CPU1_SB_DQ<31>
  VSS126  = GND
  G1  = GND
  G2  = GND
  G3  = GND

(kicad_pcb
	(version 20260206)
	(generator "pcbnew")
	(generator_version "10.0")
	(general
		(thickness 1.6)
		(legacy_teardrops no)
	)
	(paper "A4")
	(title_block
		(title "04192023_DAF0TMB3IC0_F0TG_MB_C_brd_V02_OCP.brd")
		(comment 1 "Grand Teton / footprint 2100 of 8354 (J24), pads 47-92 of 291")
	)
	(layers
		(0 "F.Cu" signal "TOP")
		(4 "In1.Cu" signal "GND")
		(6 "In2.Cu" signal "IN1")
		(8 "In3.Cu" signal "GND1")
		(10 "In4.Cu" signal "IN2")
		(12 "In5.Cu" signal "GND2")
		(14 "In6.Cu" signal "IN3")
		(16 "In7.Cu" signal "GND3")
		(18 "In8.Cu" signal "VCC")
		(20 "In9.Cu" signal "VCC1")
		(22 "In10.Cu" signal "GND4")
		(24 "In11.Cu" signal "IN4")
		(26 "In12.Cu" signal "GND5")
		(28 "In13.Cu" signal "IN5")
		(30 "In14.Cu" signal "GND6")
		(32 "In15.Cu" signal "IN6")
		(34 "In16.Cu" signal "GND7")
		(2 "B.Cu" signal "BOTTOM")
		(9 "F.Adhes" user "F.Adhesive")
		(11 "B.Adhes" user "B.Adhesive")
		(13 "F.Paste" user "Package Geometry/Pastemask Top")
		(15 "B.Paste" user "Package Geometry/Pastemask Bottom")
		(5 "F.SilkS" user "Ref Des/Silkscreen Top")
		(7 "B.SilkS" user "Ref Des/Silkscreen Bottom")
		(1 "F.Mask" user "Board Geometry/Soldermask Top")
		(3 "B.Mask" user "Board Geometry/Soldermask Bottom")
		(17 "Dwgs.User" user "User.Drawings")
		(19 "Cmts.User" user "User.Comments")
		(21 "Eco1.User" user "User.Eco1")
		(23 "Eco2.User" user "User.Eco2")
		(25 "Edge.Cuts" user "Board Geometry/Outline")
		(27 "Margin" user)
		(31 "F.CrtYd" user "Package Geometry/Place Bound Top")
		(29 "B.CrtYd" user "Package Geometry/Place Bound Bottom")
		(35 "F.Fab" user "Ref Des/Assembly Top")
		(33 "B.Fab" user "Ref Des/Assembly Bottom")
	)
	(footprint ""
		(layer "F.Cu")
		(at 57.378092 -255.560322 180)
		(property "Reference" "J24"
			(at 1.914906 -84.58708 0)
			(unlocked yes)
			(layer "F.SilkS")
			(effects
				(font
					(size 0.7874 0.5842)
					(thickness 0.1524)
				)
			)
		)
		(property "Value" ""
			(at 0 0 180)
			(layer "F.Fab")
			(effects
				(font
					(size 1.27 1.27)
				)
			)
		)
		(duplicate_pad_numbers_are_jumpers no)
		(pad "47" smd rect
			(at -2.050034 -24.224996 90)
			(size 0.519938 1.4986)
			(layers "F.Cu" "F.Mask" "F.Paste")
			(net "M_A_CPU1_SA_DQ<28>")
		)
		(pad "48" smd rect
			(at -2.050034 -23.375112 90)
			(size 0.519938 1.4986)
			(layers "F.Cu" "F.Mask" "F.Paste")
			(net "GND")
		)
		(pad "49" smd rect
			(at -2.050034 -22.524974 90)
			(size 0.519938 1.4986)
			(layers "F.Cu" "F.Mask" "F.Paste")
			(net "M_A_CPU1_SA_DQ<29>")
		)
		(pad "50" smd rect
			(at -2.050034 -21.67509 90)
			(size 0.519938 1.4986)
			(layers "F.Cu" "F.Mask" "F.Paste")
			(net "GND")
		)
		(pad "51" smd rect
			(at -2.050034 -20.824952 90)
			(size 0.519938 1.4986)
			(layers "F.Cu" "F.Mask" "F.Paste")
			(net "M_A_CPU1_SA_CB<0>")
		)
		(pad "52" smd rect
			(at -2.050034 -19.975068 90)
			(size 0.519938 1.4986)
			(layers "F.Cu" "F.Mask" "F.Paste")
			(net "GND")
		)
		(pad "53" smd rect
			(at -2.050034 -19.12493 90)
			(size 0.519938 1.4986)
			(layers "F.Cu" "F.Mask" "F.Paste")
			(net "M_A_CPU1_SA_CB<1>")
		)
		(pad "54" smd rect
			(at -2.050034 -18.275046 90)
			(size 0.519938 1.4986)
			(layers "F.Cu" "F.Mask" "F.Paste")
			(net "GND")
		)
		(pad "55" smd rect
			(at -2.050034 -17.424908 90)
			(size 0.519938 1.4986)
			(layers "F.Cu" "F.Mask" "F.Paste")
			(net "M_A_CPU1_SA_DQS_DP<4>")
		)
		(pad "56" smd rect
			(at -2.050034 -16.575024 90)
			(size 0.519938 1.4986)
			(layers "F.Cu" "F.Mask" "F.Paste")
			(net "M_A_CPU1_SA_DQS_DN<4>")
		)
		(pad "57" smd rect
			(at -2.050034 -15.724886 90)
			(size 0.519938 1.4986)
			(layers "F.Cu" "F.Mask" "F.Paste")
			(net "GND")
		)
		(pad "58" smd rect
			(at -2.050034 -14.875002 90)
			(size 0.519938 1.4986)
			(layers "F.Cu" "F.Mask" "F.Paste")
			(net "M_A_CPU1_SA_CB<4>")
		)
		(pad "59" smd rect
			(at -2.050034 -14.025118 90)
			(size 0.519938 1.4986)
			(layers "F.Cu" "F.Mask" "F.Paste")
			(net "GND")
		)
		(pad "60" smd rect
			(at -2.050034 -13.17498 90)
			(size 0.519938 1.4986)
			(layers "F.Cu" "F.Mask" "F.Paste")
			(net "M_A_CPU1_SA_CB<5>")
		)
		(pad "61" smd rect
			(at -2.050034 -12.325096 90)
			(size 0.519938 1.4986)
			(layers "F.Cu" "F.Mask" "F.Paste")
			(net "GND")
		)
		(pad "62" smd rect
			(at -2.050034 -11.474958 90)
			(size 0.519938 1.4986)
			(layers "F.Cu" "F.Mask" "F.Paste")
			(net "M_A_CPU1_ALERT_N")
		)
		(pad "63" smd rect
			(at -2.050034 -10.625074 90)
			(size 0.519938 1.4986)
			(layers "F.Cu" "F.Mask" "F.Paste")
			(net "GND")
		)
		(pad "64" smd rect
			(at -2.050034 -9.774936 90)
			(size 0.519938 1.4986)
			(layers "F.Cu" "F.Mask" "F.Paste")
			(net "M_A_CPU1_SA_CS_N<0>")
		)
		(pad "65" smd rect
			(at -2.050034 -8.925052 90)
			(size 0.519938 1.4986)
			(layers "F.Cu" "F.Mask" "F.Paste")
			(net "GND")
		)
		(pad "66" smd rect
			(at -2.050034 -8.074914 90)
			(size 0.519938 1.4986)
			(layers "F.Cu" "F.Mask" "F.Paste")
			(net "M_A_CPU1_SA_CA<0>")
		)
		(pad "67" smd rect
			(at -2.050034 -7.22503 90)
			(size 0.519938 1.4986)
			(layers "F.Cu" "F.Mask" "F.Paste")
			(net "GND")
		)
		(pad "68" smd rect
			(at -2.050034 -6.374892 90)
			(size 0.519938 1.4986)
			(layers "F.Cu" "F.Mask" "F.Paste")
			(net "M_A_CPU1_SA_CA<2>")
		)
		(pad "69" smd rect
			(at -2.050034 -5.525008 90)
			(size 0.519938 1.4986)
			(layers "F.Cu" "F.Mask" "F.Paste")
			(net "GND")
		)
		(pad "70" smd rect
			(at -2.050034 -4.675124 90)
			(size 0.519938 1.4986)
			(layers "F.Cu" "F.Mask" "F.Paste")
			(net "M_A_CPU1_SA_CA<4>")
		)
		(pad "71" smd rect
			(at -2.050034 -3.824986 90)
			(size 0.519938 1.4986)
			(layers "F.Cu" "F.Mask" "F.Paste")
			(net "GND")
		)
		(pad "72" smd rect
			(at -2.050034 -2.975102 90)
			(size 0.519938 1.4986)
			(layers "F.Cu" "F.Mask" "F.Paste")
			(net "M_A_CPU1_SA_CA<6>")
		)
		(pad "73" smd rect
			(at -2.050034 -2.124964 90)
			(size 0.519938 1.4986)
			(layers "F.Cu" "F.Mask" "F.Paste")
			(net "GND")
		)
		(pad "74" smd rect
			(at -2.050034 -1.27508 90)
			(size 0.519938 1.4986)
			(layers "F.Cu" "F.Mask" "F.Paste")
			(net "M_A_CPU1_SA_PAR")
		)
		(pad "75" smd rect
			(at -2.050034 -0.424942 90)
			(size 0.519938 1.4986)
			(layers "F.Cu" "F.Mask" "F.Paste")
			(net "GND")
		)
		(pad "76" smd rect
			(at -2.050034 5.525008 90)
			(size 0.519938 1.4986)
			(layers "F.Cu" "F.Mask" "F.Paste")
			(net "M_A_CPU1_SB_CA<0>")
		)
		(pad "77" smd rect
			(at -2.050034 6.374892 90)
			(size 0.519938 1.4986)
			(layers "F.Cu" "F.Mask" "F.Paste")
			(net "GND")
		)
		(pad "78" smd rect
			(at -2.050034 7.22503 90)
			(size 0.519938 1.4986)
			(layers "F.Cu" "F.Mask" "F.Paste")
			(net "M_A_CPU1_SB_CA<2>")
		)
		(pad "79" smd rect
			(at -2.050034 8.074914 90)
			(size 0.519938 1.4986)
			(layers "F.Cu" "F.Mask" "F.Paste")
			(net "GND")
		)
		(pad "80" smd rect
			(at -2.050034 8.925052 90)
			(size 0.519938 1.4986)
			(layers "F.Cu" "F.Mask" "F.Paste")
			(net "M_A_CPU1_SB_CA<4>")
		)
		(pad "81" smd rect
			(at -2.050034 9.774936 90)
			(size 0.519938 1.4986)
			(layers "F.Cu" "F.Mask" "F.Paste")
			(net "GND")
		)
		(pad "82" smd rect
			(at -2.050034 10.625074 90)
			(size 0.519938 1.4986)
			(layers "F.Cu" "F.Mask" "F.Paste")
			(net "M_A_CPU1_SB_CA<6>")
		)
		(pad "83" smd rect
			(at -2.050034 11.474958 90)
			(size 0.519938 1.4986)
			(layers "F.Cu" "F.Mask" "F.Paste")
			(net "GND")
		)
		(pad "84" smd rect
			(at -2.050034 12.325096 90)
			(size 0.519938 1.4986)
			(layers "F.Cu" "F.Mask" "F.Paste")
			(net "M_A_CPU1_SB_CS_N<0>")
		)
		(pad "85" smd rect
			(at -2.050034 13.17498 90)
			(size 0.519938 1.4986)
			(layers "F.Cu" "F.Mask" "F.Paste")
			(net "GND")
		)
		(pad "86" smd rect
			(at -2.050034 14.025118 90)
			(size 0.519938 1.4986)
			(layers "F.Cu" "F.Mask" "F.Paste")
			(net "M_A_CPU1_SA_RSP<0>")
		)
		(pad "87" smd rect
			(at -2.050034 14.875002 90)
			(size 0.519938 1.4986)
			(layers "F.Cu" "F.Mask" "F.Paste")
			(net "M_A_CPU1_SB_RSP<0>")
		)
		(pad "88" smd rect
			(at -2.050034 15.724886 90)
			(size 0.519938 1.4986)
			(layers "F.Cu" "F.Mask" "F.Paste")
			(net "GND")
		)
		(pad "89" smd rect
			(at -2.050034 16.575024 90)
			(size 0.519938 1.4986)
			(layers "F.Cu" "F.Mask" "F.Paste")
			(net "M_A_CPU1_SB_CB<4>")
		)
		(pad "90" smd rect
			(at -2.050034 17.424908 90)
			(size 0.519938 1.4986)
			(layers "F.Cu" "F.Mask" "F.Paste")
			(net "GND")
		)
		(pad "91" smd rect
			(at -2.050034 18.275046 90)
			(size 0.519938 1.4986)
			(layers "F.Cu" "F.Mask" "F.Paste")
			(net "M_A_CPU1_SB_CB<5>")
		)
		(pad "92" smd rect
			(at -2.050034 19.12493 90)
			(size 0.519938 1.4986)
			(layers "F.Cu" "F.Mask" "F.Paste")
			(net "GND")
		)
	)
)
